# S9S_MB_2U (Grand Teton) — schematic netlist excerpt (pin names and nets, part order shuffled) for the footprints in the layout excerpt that follows; sources: Cadence DE-HDL packaged netlist, KiCad conversion of 03242023_DA0F0TMBIJ0_F0T_Motherboard_J_brd_V01_OCP.brd

J7  SCONN288_ADR50017P130CC  SCONN288_ADR50017-P130CC IO  pkg DDR288S_1-1VXB  page 88
  VIN_BULK0  = P12V_S3_AUX_CPU0_NVDIMM
  RFU0  = TP_CHD_CPU0_DIMM1_FRU_0
  VIN_MGMT  = P3V3_AUX
  HSCL  = I3C_SPD_DDRABCD_CPU0_LVC1_SCL_6
  HSDA  = I3C_SPD_DDRABCD_CPU0_LVC1_SDA
  VSS0  = GND
  DQ0_A  = M_D_CPU0_SA_DQ<0>
  VSS1  = GND
  DQ1_A  = M_D_CPU0_SA_DQ<1>
  VSS2  = GND
  DQS0_A_T  = M_D_CPU0_SA_DQS_DP<0>
  DQS0_A_C  = M_D_CPU0_SA_DQS_DN<0>
  VSS3  = GND
  DQ4_A  = M_D_CPU0_SA_DQ<4>
  VSS4  = GND
  DQ5_A  = M_D_CPU0_SA_DQ<5>
  VSS5  = GND
  DQ8_A  = M_D_CPU0_SA_DQ<8>
  VSS6  = GND
  DQ9_A  = M_D_CPU0_SA_DQ<9>
  VSS7  = GND
  DQS1_A_T  = M_D_CPU0_SA_DQS_DP<1>
  DQS1_A_C  = M_D_CPU0_SA_DQS_DN<1>
  VSS8  = GND
  DQ12_A  = M_D_CPU0_SA_DQ<12>
  VSS9  = GND
  DQ13_A  = M_D_CPU0_SA_DQ<13>
  VSS10  = GND
  DQ16_A  = M_D_CPU0_SA_DQ<16>
  VSS11  = GND
  DQ17_A  = M_D_CPU0_SA_DQ<17>
  VSS12  = GND
  DQS2_A_T  = M_D_CPU0_SA_DQS_DP<2>
  DQS2_A_C  = M_D_CPU0_SA_DQS_DN<2>
  VSS13  = GND
  DQ20_A  = M_D_CPU0_SA_DQ<20>
  VSS14  = GND
  DQ21_A  = M_D_CPU0_SA_DQ<21>
  VSS15  = GND
  DQ24_A  = M_D_CPU0_SA_DQ<24>
  VSS16  = GND
  DQ25_A  = M_D_CPU0_SA_DQ<25>
  VSS17  = GND
  DQS3_A_T  = M_D_CPU0_SA_DQS_DP<3>
  DQS3_A_C  = M_D_CPU0_SA_DQS_DN<3>
  VSS18  = GND
  DQ28_A  = M_D_CPU0_SA_DQ<28>
  VSS19  = GND
  DQ29_A  = M_D_CPU0_SA_DQ<29>
  VSS20  = GND
  CB0_A  = M_D_CPU0_SA_CB<0>
  VSS21  = GND
  CB1_A  = M_D_CPU0_SA_CB<1>
  VSS22  = GND
  DQS4_A_T  = M_D_CPU0_SA_DQS_DP<4>
  DQS4_A_C  = M_D_CPU0_SA_DQS_DN<4>
  VSS23  = GND
  CB4_A  = M_D_CPU0_SA_CB<4>
  VSS24  = GND
  CB5_A  = M_D_CPU0_SA_CB<5>
  VSS25  = GND
  ALERT_N  = M_D_CPU0_ALERT_N
  VSS26  = GND
  CS0_A_N  = M_D_CPU0_SA_CS_N<0>
  VSS27  = GND
  CA0_A  = M_D_CPU0_SA_CA<0>
  VSS28  = GND
  CA2_A  = M_D_CPU0_SA_CA<2>
  VSS29  = GND
  CA4_A  = M_D_CPU0_SA_CA<4>
  VSS30  = GND
  CA6_A  = M_D_CPU0_SA_CA<6>
  VSS31  = GND
  PAR_A  = M_D_CPU0_SA_PAR
  VSS32  = GND
  CA0_B  = M_D_CPU0_SB_CA<0>
  VSS33  = GND
  CA2_B  = M_D_CPU0_SB_CA<2>
  VSS34  = GND
  CA4_B  = M_D_CPU0_SB_CA<4>
  VSS35  = GND
  CA6_B  = M_D_CPU0_SB_CA<6>
  VSS36  = GND
  CS0_B_N  = M_D_CPU0_SB_CS_N<0>
  VSS37  = GND
  \lbd||rsp_a_n\  = M_D_CPU0_SA_RSP<0>
  \lbs||rsp_b_n\  = M_D_CPU0_SB_RSP<0>
  VSS38  = GND
  CB4_B  = M_D_CPU0_SB_CB<4>
  VSS39  = GND
  CB5_B  = M_D_CPU0_SB_CB<5>
  VSS40  = GND
  \dqs9_b_t||tdqs9_b_t||dbi4_b_n\  = M_D_CPU0_SB_DQS_DP<9>
  \dqs9_b_c||tdqs9_b_c\  = M_D_CPU0_SB_DQS_DN<9>
  VSS41  = GND
  CB0_B  = M_D_CPU0_SB_CB<0>
  VSS42  = GND
  CB1_B  = M_D_CPU0_SB_CB<1>
  VSS43  = GND
  DQ0_B  = M_D_CPU0_SB_DQ<0>
  VSS44  = GND
  DQ1_B  = M_D_CPU0_SB_DQ<1>
  VSS45  = GND
  DQS0_B_T  = M_D_CPU0_SB_DQS_DP<0>
  DQS0_B_C  = M_D_CPU0_SB_DQS_DN<0>
  VSS46  = GND
  DQ4_B  = M_D_CPU0_SB_DQ<4>
  VSS47  = GND
  DQ5_B  = M_D_CPU0_SB_DQ<5>
  VSS48  = GND
  DQ8_B  = M_D_CPU0_SB_DQ<8>
  VSS49  = GND
  DQ9_B  = M_D_CPU0_SB_DQ<9>
  VSS50  = GND
  DQS1_B_T  = M_D_CPU0_SB_DQS_DP<1>
  DQS1_B_C  = M_D_CPU0_SB_DQS_DN<1>
  VSS51  = GND
  DQ12_B  = M_D_CPU0_SB_DQ<12>
  VSS52  = GND
  DQ13_B  = M_D_CPU0_SB_DQ<13>
  VSS53  = GND
  DQ16_B  = M_D_CPU0_SB_DQ<16>
  VSS54  = GND
  DQ17_B  = M_D_CPU0_SB_DQ<17>
  VSS55  = GND
  DQS2_B_T  = M_D_CPU0_SB_DQS_DP<2>
  DQS2_B_C  = M_D_CPU0_SB_DQS_DN<2>
  VSS56  = GND
  DQ20_B  = M_D_CPU0_SB_DQ<20>
  VSS57  = GND
  DQ21_B  = M_D_CPU0_SB_DQ<21>
  VSS58  = GND
  DQ24_B  = M_D_CPU0_SB_DQ<24>
  VSS59  = GND
  DQ25_B  = M_D_CPU0_SB_DQ<25>
  VSS60  = GND
  DQS3_B_T  = M_D_CPU0_SB_DQS_DP<3>
  DQS3_B_C  = M_D_CPU0_SB_DQS_DN<3>
  VSS61  = GND
  DQ28_B  = M_D_CPU0_SB_DQ<28>
  VSS62  = GND
  DQ29_B  = M_D_CPU0_SB_DQ<29>
  VSS63  = GND
  RFU1  = TP_CHD_CPU0_DIMM1_FRU_1
  VIN_BULK1  = P12V_S3_AUX_CPU0_NVDIMM
  VIN_BULK2  = P12V_S3_AUX_CPU0_NVDIMM
  \pwr_good||fail_n\  = PWRGD_CHD_CPU0_DIMM1
  HSA  = PD_CHD_CPU0_DIMM1_SAA
  RFU2  = TP_CHD_CPU0_DIMM1_FRU_2
  RFU3  = TP_CHD_CPU0_DIMM1_FRU_3
  VSS64  = GND
  DQ2_A  = M_D_CPU0_SA_DQ<2>
  VSS65  = GND
  DQ3_A  = M_D_CPU0_SA_DQ<3>
  VSS66  = GND
  \dqs5_a_c||tdqs5_a_c||dqs5_a_t||tdqs5_a_t\  = M_D_CPU0_SA_DQS_DN<5>
  \dqs5_a_t||tdqs5_a_t\  = M_D_CPU0_SA_DQS_DP<5>
  VSS67  = GND
  DQ6_A  = M_D_CPU0_SA_DQ<6>
  VSS68  = GND
  DQ7_A  = M_D_CPU0_SA_DQ<7>
  VSS69  = GND
  DQ10_A  = M_D_CPU0_SA_DQ<10>
  VSS70  = GND
  DQ11_A  = M_D_CPU0_SA_DQ<11>
  VSS71  = GND
  \dqs6_a_c||tdqs6_a_c||dqs6_a_t||tdqs6_a_t\  = M_D_CPU0_SA_DQS_DN<6>
  \dqs6_a_t||tdqs6_a_t\  = M_D_CPU0_SA_DQS_DP<6>
  VSS72  = GND
  DQ14_A  = M_D_CPU0_SA_DQ<14>
  VSS73  = GND
  DQ15_A  = M_D_CPU0_SA_DQ<15>
  VSS74  = GND
  DQ18_A  = M_D_CPU0_SA_DQ<18>
  VSS75  = GND
  DQ19_A  = M_D_CPU0_SA_DQ<19>
  VSS76  = GND
  \dqs7_a_c||tdqs7_a_c\  = M_D_CPU0_SA_DQS_DN<7>
  \dqs7_a_t||tdqs7_a_t\  = M_D_CPU0_SA_DQS_DP<7>
  VSS77  = GND
  DQ22_A  = M_D_CPU0_SA_DQ<22>
  VSS78  = GND
  DQ23_A  = M_D_CPU0_SA_DQ<23>
  VSS79  = GND
  DQ26_A  = M_D_CPU0_SA_DQ<26>
  VSS80  = GND
  DQ27_A  = M_D_CPU0_SA_DQ<27>
  VSS81  = GND
  \dqs8_a_c||tdqs8_a_c\  = M_D_CPU0_SA_DQS_DN<8>
  \dqs8_a_t||tdqs8_a_t\  = M_D_CPU0_SA_DQS_DP<8>
  VSS82  = GND
  DQ30_A  = M_D_CPU0_SA_DQ<30>
  VSS83  = GND
  DQ31_A  = M_D_CPU0_SA_DQ<31>
  VSS84  = GND
  CB2_A  = M_D_CPU0_SA_CB<2>
  VSS85  = GND
  CB3_A  = M_D_CPU0_SA_CB<3>
  VSS86  = GND
  \dqs9_a_c||tdqs9_a_c\  = M_D_CPU0_SA_DQS_DN<9>
  \dqs9_a_t||tdqs9_a_t\  = M_D_CPU0_SA_DQS_DP<9>
  VSS87  = GND
  CB6_A  = M_D_CPU0_SA_CB<6>
  VSS88  = GND
  CB7_A  = M_D_CPU0_SA_CB<7>
  VSS89  = GND
  RESET_N  = RST_M_CD_CPU0_FPGA_N
  VSS90  = GND
  CS1_A_N  = M_D_CPU0_SA_CS_N<1>
  VSS91  = GND
  CA1_A  = M_D_CPU0_SA_CA<1>
  VSS92  = GND
  CA3_A  = M_D_CPU0_SA_CA<3>
  VSS93  = GND
  CA5_A  = M_D_CPU0_SA_CA<5>
  VSS94  = GND
  CK_T  = M_D_CPU0_CLK_DP<0>
  CK_C  = M_D_CPU0_CLK_DN<0>
  VSS95  = GND
  RFU4  = TP_CHD_CPU0_DIMM1_FRU_4
  CA1_B  = M_D_CPU0_SB_CA<1>
  VSS96  = GND
  CA3_B  = M_D_CPU0_SB_CA<3>
  VSS97  = GND
  CA5_B  = M_D_CPU0_SB_CA<5>
  VSS98  = GND
  PAR_B  = M_D_CPU0_SB_PAR
  VSS99  = GND
  CS1_B_N  = M_D_CPU0_SB_CS_N<1>
  VSS100  = GND
  RFU5  = TP_CHD_CPU0_DIMM1_FRU_5
  RFU6  = TP_CHD_CPU0_DIMM1_FRU_6
  VSS101  = GND
  CB6_B  = M_D_CPU0_SB_CB<6>
  VSS102  = GND
  CB7_B  = M_D_CPU0_SB_CB<7>
  VSS103  = GND
  DQS4_B_C  = M_D_CPU0_SB_DQS_DN<4>
  DQS4_B_T  = M_D_CPU0_SB_DQS_DP<4>
  VSS104  = GND
  CB2_B  = M_D_CPU0_SB_CB<2>
  VSS105  = GND
  CB3_B  = M_D_CPU0_SB_CB<3>
  VSS106  = GND
  DQ2_B  = M_D_CPU0_SB_DQ<2>
  VSS107  = GND
  DQ3_B  = M_D_CPU0_SB_DQ<3>
  VSS108  = GND
  \dqs5_b_c||tdqs5_b_c\  = M_D_CPU0_SB_DQS_DN<5>
  \dqs5_b_t||tdqs5_b_t\  = M_D_CPU0_SB_DQS_DP<5>
  VSS109  = GND
  DQ6_B  = M_D_CPU0_SB_DQ<6>
  VSS110  = GND
  DQ7_B  = M_D_CPU0_SB_DQ<7>
  VSS111  = GND
  DQ10_B  = M_D_CPU0_SB_DQ<10>
  VSS112  = GND
  DQ11_B  = M_D_CPU0_SB_DQ<11>
  VSS113  = GND
  \dqs6_b_c||tdqs6_b_c\  = M_D_CPU0_SB_DQS_DN<6>
  \dqs6_b_t||tdqs6_b_t\  = M_D_CPU0_SB_DQS_DP<6>
  VSS114  = GND
  DQ14_B  = M_D_CPU0_SB_DQ<14>
  VSS115  = GND
  DQ15_B  = M_D_CPU0_SB_DQ<15>
  VSS116  = GND
  DQ18_B  = M_D_CPU0_SB_DQ<18>
  VSS117  = GND
  DQ19_B  = M_D_CPU0_SB_DQ<19>
  VSS118  = GND
  \dqs7_b_c||tdqs7_b_c\  = M_D_CPU0_SB_DQS_DN<7>
  \dqs7_b_t||tdqs7_b_t\  = M_D_CPU0_SB_DQS_DP<7>
  VSS119  = GND
  DQ22_B  = M_D_CPU0_SB_DQ<22>
  VSS120  = GND
  DQ23_B  = M_D_CPU0_SB_DQ<23>
  VSS121  = GND
  DQ26_B  = M_D_CPU0_SB_DQ<26>
  VSS122  = GND
  DQ27_B  = M_D_CPU0_SB_DQ<27>
  VSS123  = GND
  \dqs8_b_c||tdqs8_b_c\  = M_D_CPU0_SB_DQS_DN<8>
  \dqs8_b_t||tdqs8_b_t\  = M_D_CPU0_SB_DQS_DP<8>
  VSS124  = GND
  DQ30_B  = M_D_CPU0_SB_DQ<30>
  VSS125  = GND
  DQ31_B  = M_D_CPU0_SB_DQ<31>
  VSS126  = GND
  G1  = GND
  G2  = GND
  G3  = GND

(kicad_pcb
	(version 20260206)
	(generator "pcbnew")
	(generator_version "10.0")
	(general
		(thickness 1.6)
		(legacy_teardrops no)
	)
	(paper "A4")
	(title_block
		(title "03242023_DA0F0TMBIJ0_F0T_Motherboard_J_brd_V01_OCP.brd")
		(comment 1 "Grand Teton / footprint 37 of 6105 (J7), pads 275-291 of 291")
	)
	(layers
		(0 "F.Cu" signal "TOP")
		(4 "In1.Cu" signal "GND")
		(6 "In2.Cu" signal "IN1")
		(8 "In3.Cu" signal "GND1")
		(10 "In4.Cu" signal "IN2")
		(12 "In5.Cu" signal "GND2")
		(14 "In6.Cu" signal "IN3")
		(16 "In7.Cu" signal "GND3")
		(18 "In8.Cu" signal "VCC")
		(20 "In9.Cu" signal "VCC1")
		(22 "In10.Cu" signal "GND4")
		(24 "In11.Cu" signal "IN4")
		(26 "In12.Cu" signal "GND5")
		(28 "In13.Cu" signal "IN5")
		(30 "In14.Cu" signal "GND6")
		(32 "In15.Cu" signal "IN6")
		(34 "In16.Cu" signal "GND7")
		(2 "B.Cu" signal "BOTTOM")
		(9 "F.Adhes" user "F.Adhesive")
		(11 "B.Adhes" user "B.Adhesive")
		(13 "F.Paste" user "Package Geometry/Pastemask Top")
		(15 "B.Paste" user "Package Geometry/Pastemask Bottom")
		(5 "F.SilkS" user "Ref Des/Silkscreen Top")
		(7 "B.SilkS" user "Ref Des/Silkscreen Bottom")
		(1 "F.Mask" user "Board Geometry/Soldermask Top")
		(3 "B.Mask" user "Board Geometry/Soldermask Bottom")
		(17 "Dwgs.User" user "User.Drawings")
		(19 "Cmts.User" user "User.Comments")
		(21 "Eco1.User" user "User.Eco1")
		(23 "Eco2.User" user "User.Eco2")
		(25 "Edge.Cuts" user "Board Geometry/Outline")
		(27 "Margin" user)
		(31 "F.CrtYd" user "Package Geometry/Place Bound Top")
		(29 "B.CrtYd" user "Package Geometry/Place Bound Bottom")
		(35 "F.Fab" user "Ref Des/Assembly Top")
		(33 "B.Fab" user "Ref Des/Assembly Bottom")
	)
	(footprint ""
		(layer "F.Cu")
		(at 258.130548 -258.091686)
		(property "Reference" "J7"
			(at -3.683 -81.702148 0)
			(unlocked yes)
			(layer "F.SilkS")
			(effects
				(font
					(size 0.7874 0.5842)
					(thickness 0.1524)
				)
				(justify left)
			)
		)
		(property "Value" ""
			(at 0 0 0)
			(layer "F.Fab")
			(effects
				(font
					(size 1.27 1.27)
				)
			)
		)
		(duplicate_pad_numbers_are_jumpers no)
		(pad "275" smd rect
			(at 2.050034 52.274978 270)
			(size 0.519938 1.4986)
			(layers "F.Cu" "F.Mask" "F.Paste")
			(net "GND")
		)
		(pad "276" smd rect
			(at 2.050034 53.125116 270)
			(size 0.519938 1.4986)
			(layers "F.Cu" "F.Mask" "F.Paste")
			(net "M_D_CPU0_SB_DQ<23>")
		)
		(pad "277" smd rect
			(at 2.050034 53.975 270)
			(size 0.519938 1.4986)
			(layers "F.Cu" "F.Mask" "F.Paste")
			(net "GND")
		)
		(pad "278" smd rect
			(at 2.050034 54.824884 270)
			(size 0.519938 1.4986)
			(layers "F.Cu" "F.Mask" "F.Paste")
			(net "M_D_CPU0_SB_DQ<26>")
		)
		(pad "279" smd rect
			(at 2.050034 55.675022 270)
			(size 0.519938 1.4986)
			(layers "F.Cu" "F.Mask" "F.Paste")
			(net "GND")
		)
		(pad "280" smd rect
			(at 2.050034 56.524906 270)
			(size 0.519938 1.4986)
			(layers "F.Cu" "F.Mask" "F.Paste")
			(net "M_D_CPU0_SB_DQ<27>")
		)
		(pad "281" smd rect
			(at 2.050034 57.375044 270)
			(size 0.519938 1.4986)
			(layers "F.Cu" "F.Mask" "F.Paste")
			(net "GND")
		)
		(pad "282" smd rect
			(at 2.050034 58.224928 270)
			(size 0.519938 1.4986)
			(layers "F.Cu" "F.Mask" "F.Paste")
			(net "M_D_CPU0_SB_DQS_DN<8>")
		)
		(pad "283" smd rect
			(at 2.050034 59.075066 270)
			(size 0.519938 1.4986)
			(layers "F.Cu" "F.Mask" "F.Paste")
			(net "M_D_CPU0_SB_DQS_DP<8>")
		)
		(pad "284" smd rect
			(at 2.050034 59.92495 270)
			(size 0.519938 1.4986)
			(layers "F.Cu" "F.Mask" "F.Paste")
			(net "GND")
		)
		(pad "285" smd rect
			(at 2.050034 60.775088 270)
			(size 0.519938 1.4986)
			(layers "F.Cu" "F.Mask" "F.Paste")
			(net "M_D_CPU0_SB_DQ<30>")
		)
		(pad "286" smd rect
			(at 2.050034 61.624972 270)
			(size 0.519938 1.4986)
			(layers "F.Cu" "F.Mask" "F.Paste")
			(net "GND")
		)
		(pad "287" smd rect
			(at 2.050034 62.47511 270)
			(size 0.519938 1.4986)
			(layers "F.Cu" "F.Mask" "F.Paste")
			(net "M_D_CPU0_SB_DQ<31>")
		)
		(pad "288" smd rect
			(at 2.050034 63.324994 270)
			(size 0.519938 1.4986)
			(layers "F.Cu" "F.Mask" "F.Paste")
			(net "GND")
		)
		(pad "G1" thru_hole oval
			(at 0 -68.97497)
			(size 2.8194 1.5748)
			(drill oval 2.4384 1.1938)
			(layers "*.Cu" "*.Mask")
			(remove_unused_layers no)
			(net "GND")
			(clearance 0.127)
			(thermal_gap 0.127)
		)
		(pad "G2" thru_hole oval
			(at 0 3.875024)
			(size 2.8194 1.5748)
			(drill oval 2.4384 1.1938)
			(layers "*.Cu" "*.Mask")
			(remove_unused_layers no)
			(net "GND")
			(clearance 0.127)
			(thermal_gap 0.127)
		)
		(pad "G3" thru_hole oval
			(at 0 68.97497)
			(size 2.8194 1.5748)
			(drill oval 2.4384 1.1938)
			(layers "*.Cu" "*.Mask")
			(remove_unused_layers no)
			(net "GND")
			(clearance 0.127)
			(thermal_gap 0.127)
		)
	)
)
